(kicad_pcb
	(version 20241229)
	(generator "pcbnew")
	(generator_version "9.0")
	(general
		(thickness 1.61)
		(legacy_teardrops no)
	)
	(paper "A3")
	(title_block
		(title "RDIMM DDR5 Tester")
		(date "2026-05-21")
		(rev "2.2.0")
		(company "Antmicro")
		(comment 9 "footprints 595-598 of 796")
	)
	(layers
		(0 "F.Cu" signal)
		(4 "In1.Cu" power)
		(6 "In2.Cu" mixed)
		(8 "In3.Cu" power)
		(10 "In4.Cu" mixed)
		(12 "In5.Cu" power)
		(14 "In6.Cu" mixed)
		(16 "In7.Cu" power)
		(18 "In8.Cu" power)
		(20 "In9.Cu" mixed)
		(22 "In10.Cu" power)
		(2 "B.Cu" signal)
		(9 "F.Adhes" user "F.Adhesive")
		(11 "B.Adhes" user "B.Adhesive")
		(13 "F.Paste" user)
		(15 "B.Paste" user)
		(5 "F.SilkS" user "F.Silkscreen")
		(7 "B.SilkS" user "B.Silkscreen")
		(1 "F.Mask" user)
		(3 "B.Mask" user)
		(17 "Dwgs.User" user "User.Drawings")
		(19 "Cmts.User" user "User.Comments")
		(21 "Eco1.User" user "User.Eco1")
		(23 "Eco2.User" user "User.Eco2")
		(25 "Edge.Cuts" user)
		(27 "Margin" user)
		(31 "F.CrtYd" user "F.Courtyard")
		(29 "B.CrtYd" user "B.Courtyard")
		(35 "F.Fab" user)
		(33 "B.Fab" user)
	)
	(footprint "antmicro-footprints:C_0402_1005Metric"
		(layer "B.Cu")
		(at 186.672499 193.2285 -90)
		(descr "Capacitor SMD 0402")
		(tags "capacitor SMD 0402")
		(property "Reference" "C250"
			(at -3.8725 -0.372002 90)
			(layer "B.SilkS")
			(effects
				(font
					(size 0.7 0.7)
					(thickness 0.15)
				)
				(justify left bottom mirror)
			)
		)
		(property "Value" "C_100n_0402"
			(at -1.022927 -2.155213 90)
			(layer "B.Fab")
			(effects
				(font
					(size 0.7 0.7)
					(thickness 0.15)
				)
				(justify left bottom mirror)
			)
		)
		(property "Datasheet" "https://www.murata.com/products/productdetail?partno=GRM155R61H104KE14%23"
			(at 0 0 270)
			(layer "F.Fab")
			(hide yes)
			(effects
				(font
					(size 1.27 1.27)
					(thickness 0.15)
				)
			)
		)
		(property "Manufacturer" "Murata"
			(at 0 0 270)
			(unlocked yes)
			(layer "B.Fab")
			(hide yes)
			(effects
				(font
					(size 1 1)
					(thickness 0.15)
				)
				(justify mirror)
			)
		)
		(property "MPN" "GRM155R61H104KE14D"
			(at 0 0 270)
			(unlocked yes)
			(layer "B.Fab")
			(hide yes)
			(effects
				(font
					(size 1 1)
					(thickness 0.15)
				)
				(justify mirror)
			)
		)
		(property "Val" "100n"
			(at 0 0 270)
			(unlocked yes)
			(layer "B.Fab")
			(hide yes)
			(effects
				(font
					(size 1 1)
					(thickness 0.15)
				)
				(justify mirror)
			)
		)
		(property "License" "Apache-2.0"
			(at 0 0 270)
			(unlocked yes)
			(layer "B.Fab")
			(hide yes)
			(effects
				(font
					(size 1 1)
					(thickness 0.15)
				)
				(justify mirror)
			)
		)
		(property "Author" "Antmicro"
			(at 0 0 270)
			(unlocked yes)
			(layer "B.Fab")
			(hide yes)
			(effects
				(font
					(size 1 1)
					(thickness 0.15)
				)
				(justify mirror)
			)
		)
		(property "Voltage" "50V"
			(at 0 0 270)
			(unlocked yes)
			(layer "B.Fab")
			(hide yes)
			(effects
				(font
					(size 1 1)
					(thickness 0.15)
				)
				(justify mirror)
			)
		)
		(property "Dielectric" "X5R"
			(at 0 0 270)
			(unlocked yes)
			(layer "B.Fab")
			(hide yes)
			(effects
				(font
					(size 1 1)
					(thickness 0.15)
				)
				(justify mirror)
			)
		)
		(sheetname "/FPGA MGT Interface/")
		(sheetfile "fpga-mgt.kicad_sch")
		(attr smd)
		(fp_rect
			(start -0.925 0.47)
			(end 0.925 -0.47)
			(stroke
				(width 0.05)
				(type default)
			)
			(fill no)
			(layer "B.CrtYd")
		)
		(fp_line
			(start -0.494 0.25)
			(end 0.504 0.25)
			(stroke
				(width 0.15)
				(type solid)
			)
			(layer "B.Fab")
		)
		(fp_line
			(start 0.504 0.25)
			(end 0.504 -0.248)
			(stroke
				(width 0.15)
				(type solid)
			)
			(layer "B.Fab")
		)
		(fp_line
			(start -0.494 -0.248)
			(end -0.494 0.25)
			(stroke
				(width 0.15)
				(type solid)
			)
			(layer "B.Fab")
		)
		(fp_line
			(start 0.504 -0.248)
			(end -0.494 -0.248)
			(stroke
				(width 0.15)
				(type solid)
			)
			(layer "B.Fab")
		)
		(fp_text user "License: Apache-2.0"
			(at -0.939 -5.799 90)
			(layer "B.Fab")
			(effects
				(font
					(size 0.7 0.7)
					(thickness 0.15)
				)
				(justify left bottom mirror)
			)
		)
		(fp_text user "Author: Antmicro"
			(at -0.939 -3.399 90)
			(layer "B.Fab")
			(effects
				(font
					(size 0.7 0.7)
					(thickness 0.15)
				)
				(justify left bottom mirror)
			)
		)
		(fp_text user "${REFERENCE}"
			(at -0.939 -4.599 90)
			(layer "B.Fab")
			(effects
				(font
					(size 0.7 0.7)
					(thickness 0.15)
				)
				(justify left bottom mirror)
			)
		)
		(pad "1" smd roundrect
			(at -0.48 0 270)
			(size 0.59 0.64)
			(layers "B.Cu" "B.Mask" "B.Paste")
			(roundrect_rratio 0.25)
			(net 470 "/FPGA MGT Interface/GTY_224_TX2_N")
			(pintype "passive")
		)
		(pad "2" smd roundrect
			(at 0.48 0 270)
			(size 0.59 0.64)
			(layers "B.Cu" "B.Mask" "B.Paste")
			(roundrect_rratio 0.25)
			(net 252 "/FPGA MGT Interface/PCIE.TXD5_N")
			(pintype "passive")
		)
	)
	(footprint "antmicro-footprints:R_0402_1005Metric_EIA"
		(layer "B.Cu")
		(at 184.5 146 180)
		(descr "Resistor SMD 0402 (1005 Metric), square (rectangular) end terminal, IPC_7351 nominal, (Body size source: IPC-SM-782 page 76, https://www.pcb-3d.com/wordpress/wp-content/uploads/ipc-sm-782a_amendment_1_and_2.pdf)")
		(tags "resistor 0402")
		(property "Reference" "R131"
			(at 0.9 -0.3 0)
			(layer "B.SilkS")
			(effects
				(font
					(size 0.7 0.7)
					(thickness 0.15)
				)
				(justify left bottom mirror)
			)
		)
		(property "Value" "R_1k_0402"
			(at 0 -1.169 0)
			(layer "B.Fab")
			(effects
				(font
					(size 0.7 0.7)
					(thickness 0.15)
				)
				(justify left bottom mirror)
			)
		)
		(property "Datasheet" "https://www.bourns.com/docs/product-datasheets/cr.pdf"
			(at 0 0 0)
			(layer "F.Fab")
			(hide yes)
			(effects
				(font
					(size 1.27 1.27)
					(thickness 0.15)
				)
			)
		)
		(property "MPN" "CR0402-FX-1001GLF"
			(at 0 0 180)
			(unlocked yes)
			(layer "B.Fab")
			(hide yes)
			(effects
				(font
					(size 1 1)
					(thickness 0.15)
				)
				(justify mirror)
			)
		)
		(property "Manufacturer" "Bourns"
			(at 0 0 180)
			(unlocked yes)
			(layer "B.Fab")
			(hide yes)
			(effects
				(font
					(size 1 1)
					(thickness 0.15)
				)
				(justify mirror)
			)
		)
		(property "License" "Apache-2.0"
			(at 0 0 180)
			(unlocked yes)
			(layer "B.Fab")
			(hide yes)
			(effects
				(font
					(size 1 1)
					(thickness 0.15)
				)
				(justify mirror)
			)
		)
		(property "Author" "Antmicro"
			(at 0 0 180)
			(unlocked yes)
			(layer "B.Fab")
			(hide yes)
			(effects
				(font
					(size 1 1)
					(thickness 0.15)
				)
				(justify mirror)
			)
		)
		(property "Val" "1k"
			(at 0 0 180)
			(unlocked yes)
			(layer "B.Fab")
			(hide yes)
			(effects
				(font
					(size 1 1)
					(thickness 0.15)
				)
				(justify mirror)
			)
		)
		(property "Tolerance" "1%"
			(at 0 0 180)
			(unlocked yes)
			(layer "B.Fab")
			(hide yes)
			(effects
				(font
					(size 1 1)
					(thickness 0.15)
				)
				(justify mirror)
			)
		)
		(sheetname "/FPGA banks HP/")
		(sheetfile "fpga-hp-banks.kicad_sch")
		(attr smd exclude_from_bom dnp)
		(fp_rect
			(start -0.95 0.45)
			(end 0.95 -0.45)
			(stroke
				(width 0.05)
				(type default)
			)
			(fill no)
			(layer "B.CrtYd")
		)
		(fp_line
			(start 0.499 0.25)
			(end 0.499 -0.249)
			(stroke
				(width 0.15)
				(type solid)
			)
			(layer "B.Fab")
		)
		(fp_line
			(start 0.499 -0.249)
			(end -0.5 -0.249)
			(stroke
				(width 0.15)
				(type solid)
			)
			(layer "B.Fab")
		)
		(fp_line
			(start -0.5 0.25)
			(end 0.499 0.25)
			(stroke
				(width 0.15)
				(type solid)
			)
			(layer "B.Fab")
		)
		(fp_line
			(start -0.5 -0.249)
			(end -0.5 0.25)
			(stroke
				(width 0.15)
				(type solid)
			)
			(layer "B.Fab")
		)
		(fp_text user "License: Apache-2.0"
			(at -0.95 -4.369 0)
			(layer "B.Fab")
			(effects
				(font
					(size 0.7 0.7)
					(thickness 0.15)
				)
				(justify left bottom mirror)
			)
		)
		(fp_text user "Author: Antmicro"
			(at -0.95 -5.569 0)
			(layer "B.Fab")
			(effects
				(font
					(size 0.7 0.7)
					(thickness 0.15)
				)
				(justify left bottom mirror)
			)
		)
		(fp_text user "${REFERENCE}"
			(at -0.95 -3.169 0)
			(layer "B.Fab")
			(effects
				(font
					(size 0.7 0.7)
					(thickness 0.15)
				)
				(justify left bottom mirror)
			)
		)
		(pad "1" smd roundrect
			(at -0.5 0 90)
			(size 0.6 0.6)
			(layers "B.Cu" "B.Mask" "B.Paste")
			(roundrect_rratio 0.25)
			(net 1 "GND")
			(pintype "passive")
		)
		(pad "2" smd roundrect
			(at 0.499 0 180)
			(size 0.6 0.6)
			(layers "B.Cu" "B.Mask" "B.Paste")
			(roundrect_rratio 0.25)
			(net 545 "/FPGA banks HP/VREF_66")
			(pintype "passive")
		)
	)
	(footprint "antmicro-footprints:C_0402_1005Metric"
		(layer "B.Cu")
		(at 185.49 167.45 90)
		(descr "Capacitor SMD 0402")
		(tags "capacitor SMD 0402")
		(property "Reference" "C290"
			(at -4 0.401999 90)
			(layer "B.SilkS")
			(effects
				(font
					(size 0.7 0.7)
					(thickness 0.15)
				)
				(justify right bottom mirror)
			)
		)
		(property "Value" "C_100n_0402"
			(at -1.022927 -2.155213 90)
			(layer "B.Fab")
			(effects
				(font
					(size 0.7 0.7)
					(thickness 0.15)
				)
				(justify right bottom mirror)
			)
		)
		(property "Datasheet" "https://www.murata.com/products/productdetail?partno=GRM155R61H104KE14%23"
			(at 0 0 90)
			(layer "F.Fab")
			(hide yes)
			(effects
				(font
					(size 1.27 1.27)
					(thickness 0.15)
				)
			)
		)
		(property "Manufacturer" "Murata"
			(at 0 0 90)
			(unlocked yes)
			(layer "B.Fab")
			(hide yes)
			(effects
				(font
					(size 1 1)
					(thickness 0.15)
				)
				(justify mirror)
			)
		)
		(property "MPN" "GRM155R61H104KE14D"
			(at 0 0 90)
			(unlocked yes)
			(layer "B.Fab")
			(hide yes)
			(effects
				(font
					(size 1 1)
					(thickness 0.15)
				)
				(justify mirror)
			)
		)
		(property "Val" "100n"
			(at 0 0 90)
			(unlocked yes)
			(layer "B.Fab")
			(hide yes)
			(effects
				(font
					(size 1 1)
					(thickness 0.15)
				)
				(justify mirror)
			)
		)
		(property "License" "Apache-2.0"
			(at 0 0 90)
			(unlocked yes)
			(layer "B.Fab")
			(hide yes)
			(effects
				(font
					(size 1 1)
					(thickness 0.15)
				)
				(justify mirror)
			)
		)
		(property "Author" "Antmicro"
			(at 0 0 90)
			(unlocked yes)
			(layer "B.Fab")
			(hide yes)
			(effects
				(font
					(size 1 1)
					(thickness 0.15)
				)
				(justify mirror)
			)
		)
		(property "Voltage" "50V"
			(at 0 0 90)
			(unlocked yes)
			(layer "B.Fab")
			(hide yes)
			(effects
				(font
					(size 1 1)
					(thickness 0.15)
				)
				(justify mirror)
			)
		)
		(property "Dielectric" "X5R"
			(at 0 0 90)
			(unlocked yes)
			(layer "B.Fab")
			(hide yes)
			(effects
				(font
					(size 1 1)
					(thickness 0.15)
				)
				(justify mirror)
			)
		)
		(sheetname "/FPGA MGT Interface/")
		(sheetfile "fpga-mgt.kicad_sch")
		(attr smd)
		(fp_rect
			(start -0.925 0.47)
			(end 0.925 -0.47)
			(stroke
				(width 0.05)
				(type default)
			)
			(fill no)
			(layer "B.CrtYd")
		)
		(fp_line
			(start 0.504 -0.248)
			(end -0.494 -0.248)
			(stroke
				(width 0.15)
				(type solid)
			)
			(layer "B.Fab")
		)
		(fp_line
			(start -0.494 -0.248)
			(end -0.494 0.25)
			(stroke
				(width 0.15)
				(type solid)
			)
			(layer "B.Fab")
		)
		(fp_line
			(start 0.504 0.25)
			(end 0.504 -0.248)
			(stroke
				(width 0.15)
				(type solid)
			)
			(layer "B.Fab")
		)
		(fp_line
			(start -0.494 0.25)
			(end 0.504 0.25)
			(stroke
				(width 0.15)
				(type solid)
			)
			(layer "B.Fab")
		)
		(fp_text user "Author: Antmicro"
			(at -0.939 -3.399 270)
			(layer "B.Fab")
			(effects
				(font
					(size 0.7 0.7)
					(thickness 0.15)
				)
				(justify left bottom mirror)
			)
		)
		(fp_text user "License: Apache-2.0"
			(at -0.939 -5.799 270)
			(layer "B.Fab")
			(effects
				(font
					(size 0.7 0.7)
					(thickness 0.15)
				)
				(justify left bottom mirror)
			)
		)
		(fp_text user "${REFERENCE}"
			(at -0.939 -4.599 270)
			(layer "B.Fab")
			(effects
				(font
					(size 0.7 0.7)
					(thickness 0.15)
				)
				(justify left bottom mirror)
			)
		)
		(pad "1" smd roundrect
			(at -0.48 0 90)
			(size 0.59 0.64)
			(layers "B.Cu" "B.Mask" "B.Paste")
			(roundrect_rratio 0.25)
			(net 290 "/FPGA MGT Interface/HDMI_OUT.D1_N")
			(pintype "passive")
		)
		(pad "2" smd roundrect
			(at 0.48 0 90)
			(size 0.59 0.64)
			(layers "B.Cu" "B.Mask" "B.Paste")
			(roundrect_rratio 0.25)
			(net 629 "/FPGA MGT Interface/HDMI_FPGA.TX1_N")
			(pintype "passive")
		)
	)
	(footprint "antmicro-footprints:C_0402_1005Metric_EIA"
		(layer "B.Cu")
		(at 193 154.5 -90)
		(descr "Capacitor SMD 0402 (1005 Metric), square (rectangular) end terminal, IPC_7351 nominal, (Body size source: IPC-SM-782 page 76, https://www.pcb-3d.com/wordpress/wp-content/uploads/ipc-sm-782a_amendment_1_and_2.pdf)")
		(tags "capacitor 0402")
		(property "Reference" "C247"
			(at -12.825 30.625 90)
			(layer "B.SilkS")
			(effects
				(font
					(size 0.7 0.7)
					(thickness 0.15)
				)
				(justify left bottom mirror)
			)
		)
		(property "Value" "C_1u_25V_0402"
			(at 0 -1.169 90)
			(layer "B.Fab")
			(effects
				(font
					(size 0.7 0.7)
					(thickness 0.15)
				)
				(justify left bottom mirror)
			)
		)
		(property "Datasheet" "https://www.murata.com/products/productdetail?partno=GRM155R61E105KE11%23"
			(at 0 0 270)
			(layer "F.Fab")
			(hide yes)
			(effects
				(font
					(size 1.27 1.27)
					(thickness 0.15)
				)
			)
		)
		(property "MPN" "GRM155R61E105KE11J"
			(at 0 0 270)
			(unlocked yes)
			(layer "B.Fab")
			(hide yes)
			(effects
				(font
					(size 1 1)
					(thickness 0.15)
				)
				(justify mirror)
			)
		)
		(property "Manufacturer" "Murata"
			(at 0 0 270)
			(unlocked yes)
			(layer "B.Fab")
			(hide yes)
			(effects
				(font
					(size 1 1)
					(thickness 0.15)
				)
				(justify mirror)
			)
		)
		(property "License" "Apache-2.0"
			(at 0 0 270)
			(unlocked yes)
			(layer "B.Fab")
			(hide yes)
			(effects
				(font
					(size 1 1)
					(thickness 0.15)
				)
				(justify mirror)
			)
		)
		(property "Author" "Antmicro"
			(at 0 0 270)
			(unlocked yes)
			(layer "B.Fab")
			(hide yes)
			(effects
				(font
					(size 1 1)
					(thickness 0.15)
				)
				(justify mirror)
			)
		)
		(property "Val" "1u"
			(at 0 0 270)
			(unlocked yes)
			(layer "B.Fab")
			(hide yes)
			(effects
				(font
					(size 1 1)
					(thickness 0.15)
				)
				(justify mirror)
			)
		)
		(property "Voltage" "25V"
			(at 0 0 270)
			(unlocked yes)
			(layer "B.Fab")
			(hide yes)
			(effects
				(font
					(size 1 1)
					(thickness 0.15)
				)
				(justify mirror)
			)
		)
		(property "Dielectric" "X5R"
			(at 0 0 270)
			(unlocked yes)
			(layer "B.Fab")
			(hide yes)
			(effects
				(font
					(size 1 1)
					(thickness 0.15)
				)
				(justify mirror)
			)
		)
		(sheetname "/FPGA power/")
		(sheetfile "fpga-power.kicad_sch")
		(attr smd)
		(fp_rect
			(start -0.95 0.45)
			(end 0.95 -0.45)
			(stroke
				(width 0.05)
				(type default)
			)
			(fill no)
			(layer "B.CrtYd")
		)
		(fp_line
			(start -0.5 0.25)
			(end 0.498 0.25)
			(stroke
				(width 0.15)
				(type solid)
			)
			(layer "B.Fab")
		)
		(fp_line
			(start 0.498 0.25)
			(end 0.498 -0.248)
			(stroke
				(width 0.15)
				(type solid)
			)
			(layer "B.Fab")
		)
		(fp_line
			(start -0.5 -0.248)
			(end -0.5 0.25)
			(stroke
				(width 0.15)
				(type solid)
			)
			(layer "B.Fab")
		)
		(fp_line
			(start 0.498 -0.248)
			(end -0.5 -0.248)
			(stroke
				(width 0.15)
				(type solid)
			)
			(layer "B.Fab")
		)
		(fp_text user "${REFERENCE}"
			(at -0.9656 -3.169 90)
			(layer "B.Fab")
			(effects
				(font
					(size 0.7 0.7)
					(thickness 0.15)
				)
				(justify left bottom mirror)
			)
		)
		(fp_text user "Author: Antmicro"
			(at -0.9656 -5.569 90)
			(layer "B.Fab")
			(effects
				(font
					(size 0.7 0.7)
					(thickness 0.15)
				)
				(justify left bottom mirror)
			)
		)
		(fp_text user "License: Apache-2.0"
			(at -0.9656 -4.369 90)
			(layer "B.Fab")
			(effects
				(font
					(size 0.7 0.7)
					(thickness 0.15)
				)
				(justify left bottom mirror)
			)
		)
		(pad "1" smd roundrect
			(at -0.5 0 180)
			(size 0.6 0.6)
			(layers "B.Cu" "B.Mask" "B.Paste")
			(roundrect_rratio 0.25)
			(net 1 "GND")
			(pintype "passive")
		)
		(pad "2" smd roundrect
			(at 0.498 0 270)
			(size 0.6 0.6)
			(layers "B.Cu" "B.Mask" "B.Paste")
			(roundrect_rratio 0.25)
			(net 553 "+0V85")
			(pintype "passive")
		)
	)
)
